(kicad_pcb
	(version 20260206)
	(generator "pcbnew")
	(generator_version "10.0")
	(general
		(thickness 1.6)
		(legacy_teardrops no)
	)
	(paper "A4")
	(title_block
		(title "12092022_DA0F0TMDCD0_F0T_Management_Board_D_brd_V3_OCP.brd")
		(comment 1 "Grand Teton / footprints 419-424 of 1440")
	)
	(layers
		(0 "F.Cu" signal "TOP")
		(4 "In1.Cu" signal "GND")
		(6 "In2.Cu" signal "IN1")
		(8 "In3.Cu" signal "GND1")
		(10 "In4.Cu" signal "IN2")
		(12 "In5.Cu" signal "VCC")
		(14 "In6.Cu" signal "VCC1")
		(16 "In7.Cu" signal "IN3")
		(18 "In8.Cu" signal "GND2")
		(20 "In9.Cu" signal "IN4")
		(22 "In10.Cu" signal "GND3")
		(2 "B.Cu" signal "BOTTOM")
		(9 "F.Adhes" user "F.Adhesive")
		(11 "B.Adhes" user "B.Adhesive")
		(13 "F.Paste" user "Package Geometry/Pastemask Top")
		(15 "B.Paste" user "Package Geometry/Pastemask Bottom")
		(5 "F.SilkS" user "Ref Des/Silkscreen Top")
		(7 "B.SilkS" user "Ref Des/Silkscreen Bottom")
		(1 "F.Mask" user "Board Geometry/Soldermask Top")
		(3 "B.Mask" user "Board Geometry/Soldermask Bottom")
		(17 "Dwgs.User" user "User.Drawings")
		(19 "Cmts.User" user "User.Comments")
		(21 "Eco1.User" user "User.Eco1")
		(23 "Eco2.User" user "User.Eco2")
		(25 "Edge.Cuts" user "Board Geometry/Outline")
		(27 "Margin" user)
		(31 "F.CrtYd" user "Package Geometry/Place Bound Top")
		(29 "B.CrtYd" user "Package Geometry/Place Bound Bottom")
		(35 "F.Fab" user "Ref Des/Assembly Top")
		(33 "B.Fab" user "Ref Des/Assembly Bottom")
	)
	(footprint ""
		(layer "F.Cu")
		(at 28.270454 -15.992602)
		(property "Reference" "R386"
			(at 0 0 0)
			(layer "F.SilkS")
			(hide yes)
			(effects
				(font
					(size 1.27 1.27)
				)
			)
		)
		(property "Value" ""
			(at 0 0 0)
			(layer "F.Fab")
			(effects
				(font
					(size 1.27 1.27)
				)
			)
		)
		(duplicate_pad_numbers_are_jumpers no)
		(fp_line
			(start -0.7874 -0.4064)
			(end 0.7874 -0.4064)
			(stroke
				(width 0.1524)
				(type default)
			)
			(layer "F.SilkS")
		)
		(fp_line
			(start 0.7874 0.4064)
			(end -0.7874 0.4064)
			(stroke
				(width 0.1524)
				(type default)
			)
			(layer "F.SilkS")
		)
		(fp_line
			(start -0.67945 -0.305054)
			(end -0.12065 -0.305054)
			(stroke
				(width 0.1)
				(type default)
			)
			(layer "F.Fab")
		)
		(fp_line
			(start -0.67945 0.3048)
			(end -0.67945 -0.305054)
			(stroke
				(width 0.1)
				(type default)
			)
			(layer "F.Fab")
		)
		(fp_line
			(start -0.12065 -0.305054)
			(end -0.12065 -0.2794)
			(stroke
				(width 0.1)
				(type default)
			)
			(layer "F.Fab")
		)
		(fp_line
			(start -0.12065 -0.2794)
			(end 0.12065 -0.2794)
			(stroke
				(width 0.1)
				(type default)
			)
			(layer "F.Fab")
		)
		(fp_line
			(start -0.12065 0.2794)
			(end -0.12065 0.3048)
			(stroke
				(width 0.1)
				(type default)
			)
			(layer "F.Fab")
		)
		(fp_line
			(start -0.12065 0.3048)
			(end -0.67945 0.3048)
			(stroke
				(width 0.1)
				(type default)
			)
			(layer "F.Fab")
		)
		(fp_line
			(start 0.120396 0.2794)
			(end -0.12065 0.2794)
			(stroke
				(width 0.1)
				(type default)
			)
			(layer "F.Fab")
		)
		(fp_line
			(start 0.120396 0.3048)
			(end 0.120396 0.2794)
			(stroke
				(width 0.1)
				(type default)
			)
			(layer "F.Fab")
		)
		(fp_line
			(start 0.12065 -0.3048)
			(end 0.67945 -0.3048)
			(stroke
				(width 0.1)
				(type default)
			)
			(layer "F.Fab")
		)
		(fp_line
			(start 0.12065 -0.2794)
			(end 0.12065 -0.3048)
			(stroke
				(width 0.1)
				(type default)
			)
			(layer "F.Fab")
		)
		(fp_line
			(start 0.67945 -0.3048)
			(end 0.67945 0.3048)
			(stroke
				(width 0.1)
				(type default)
			)
			(layer "F.Fab")
		)
		(fp_line
			(start 0.67945 0.3048)
			(end 0.120396 0.3048)
			(stroke
				(width 0.1)
				(type default)
			)
			(layer "F.Fab")
		)
		(pad "1" smd circle
			(at -0.40005 0)
			(size 0 0)
			(layers "F.Cu" "F.Mask" "F.Paste")
			(net "USB_FPNL_DP")
		)
		(pad "2" smd circle
			(at 0.40005 0)
			(size 0 0)
			(layers "F.Cu" "F.Mask" "F.Paste")
			(net "USB2_01_F_DP")
		)
	)
	(footprint ""
		(layer "F.Cu")
		(at 7.79907 -64.787018 90)
		(property "Reference" "PU1"
			(at 3.716782 3.4544 90)
			(unlocked yes)
			(layer "F.SilkS")
			(effects
				(font
					(size 0.7874 0.5842)
					(thickness 0.1524)
				)
				(justify left)
			)
		)
		(property "Value" ""
			(at 0 0 90)
			(layer "F.Fab")
			(effects
				(font
					(size 1.27 1.27)
				)
			)
		)
		(duplicate_pad_numbers_are_jumpers no)
		(fp_line
			(start 1.050036 -1.549908)
			(end 1.050036 -1.253998)
			(stroke
				(width 0.1524)
				(type default)
			)
			(layer "F.SilkS")
		)
		(fp_line
			(start 0.503936 -1.549908)
			(end 1.050036 -1.549908)
			(stroke
				(width 0.1524)
				(type default)
			)
			(layer "F.SilkS")
		)
		(fp_line
			(start -1.050036 -1.549908)
			(end -0.503936 -1.549908)
			(stroke
				(width 0.1524)
				(type default)
			)
			(layer "F.SilkS")
		)
		(fp_line
			(start -1.050036 -1.253998)
			(end -1.050036 -1.549908)
			(stroke
				(width 0.1524)
				(type default)
			)
			(layer "F.SilkS")
		)
		(fp_line
			(start 1.050036 1.253998)
			(end 1.050036 1.549908)
			(stroke
				(width 0.1524)
				(type default)
			)
			(layer "F.SilkS")
		)
		(fp_line
			(start 1.050036 1.549908)
			(end 0.503936 1.549908)
			(stroke
				(width 0.1524)
				(type default)
			)
			(layer "F.SilkS")
		)
		(fp_line
			(start -0.503936 1.549908)
			(end -1.050036 1.549908)
			(stroke
				(width 0.1524)
				(type default)
			)
			(layer "F.SilkS")
		)
		(fp_line
			(start -1.050036 1.549908)
			(end -1.050036 1.253998)
			(stroke
				(width 0.1524)
				(type default)
			)
			(layer "F.SilkS")
		)
		(fp_poly
			(pts
				(xy -2.019808 -1.80086) (xy -1.341374 -2.148078) (xy -1.3335 -1.296162)
			)
			(stroke
				(width 0)
				(type default)
			)
			(fill yes)
			(layer "F.SilkS")
		)
		(fp_line
			(start 1.050036 -1.549908)
			(end 1.050036 1.549908)
			(stroke
				(width 0.1)
				(type default)
			)
			(layer "F.Fab")
		)
		(fp_line
			(start -1.050036 -1.549908)
			(end 1.050036 -1.549908)
			(stroke
				(width 0.1)
				(type default)
			)
			(layer "F.Fab")
		)
		(fp_line
			(start 1.050036 1.549908)
			(end -1.050036 1.549908)
			(stroke
				(width 0.1)
				(type default)
			)
			(layer "F.Fab")
		)
		(fp_line
			(start -1.050036 1.549908)
			(end -1.050036 -1.549908)
			(stroke
				(width 0.1)
				(type default)
			)
			(layer "F.Fab")
		)
		(fp_poly
			(pts
				(xy -2.2352 -0.618998) (xy -2.2352 -1.380998) (xy -1.4732 -0.999998)
			)
			(stroke
				(width 0)
				(type default)
			)
			(fill yes)
			(layer "F.Fab")
		)
		(pad "1" smd circle
			(at -0.94996 -0.999998)
			(size 0 0)
			(layers "F.Cu" "F.Mask" "F.Paste")
			(net "GND")
		)
		(pad "2" smd rect
			(at -0.849884 -0.499872 180)
			(size 0.254 0.9144)
			(layers "F.Cu" "F.Mask" "F.Paste")
			(net "SW_P3V3_AUX_SW")
		)
		(pad "3" smd rect
			(at -0.649986 0 180)
			(size 0.254 1.3208)
			(layers "F.Cu" "F.Mask" "F.Paste")
			(net "SW_P3V3_AUX_FLT")
		)
		(pad "4" smd rect
			(at -0.849884 0.499872 180)
			(size 0.254 0.9144)
			(layers "F.Cu" "F.Mask" "F.Paste")
			(net "P3V3_AUX_CS")
		)
		(pad "5" smd circle
			(at -0.94996 0.999998)
			(size 0 0)
			(layers "F.Cu" "F.Mask" "F.Paste")
			(net "PWRGD_EN_P3V3_R")
		)
		(pad "6" smd circle
			(at -0.249936 1.450086 90)
			(size 0 0)
			(layers "F.Cu" "F.Mask" "F.Paste")
			(net "P3V3_AUX_FB_RC")
		)
		(pad "7" smd circle
			(at 0.249936 1.450086 90)
			(size 0 0)
			(layers "F.Cu" "F.Mask" "F.Paste")
			(net "GND")
		)
		(pad "8" smd circle
			(at 0.94996 0.999998 180)
			(size 0 0)
			(layers "F.Cu" "F.Mask" "F.Paste")
			(net "P3V3_AUX_REF")
		)
		(pad "9" smd rect
			(at 0.849884 0.499872 180)
			(size 0.254 0.9144)
			(layers "F.Cu" "F.Mask" "F.Paste")
			(net "PWRGD_P3V3_AUX_R")
		)
		(pad "10" smd rect
			(at 0.849884 0 180)
			(size 0.254 0.9144)
			(layers "F.Cu" "F.Mask" "F.Paste")
			(net "SW_P3V3_AUX_BST_R")
		)
		(pad "11" smd rect
			(at 0.849884 -0.499872 180)
			(size 0.254 0.9144)
			(layers "F.Cu" "F.Mask" "F.Paste")
			(net "SW_P3V3_AUX_SW")
		)
		(pad "12" smd circle
			(at 0.94996 -0.999998 180)
			(size 0 0)
			(layers "F.Cu" "F.Mask" "F.Paste")
			(net "P3V3_AUX_MODE")
		)
		(pad "13" smd circle
			(at 0.249936 -1.450086 270)
			(size 0 0)
			(layers "F.Cu" "F.Mask" "F.Paste")
			(net "P3V3_AUX_VCC")
		)
		(pad "14" smd circle
			(at -0.249936 -1.450086 270)
			(size 0 0)
			(layers "F.Cu" "F.Mask" "F.Paste")
			(net "GND")
		)
	)
	(footprint ""
		(layer "F.Cu")
		(at 51.562 -85.9028 180)
		(property "Reference" "J1"
			(at 3.6322 -1.44907 0)
			(unlocked yes)
			(layer "F.SilkS")
			(effects
				(font
					(size 0.7874 0.5842)
					(thickness 0.1524)
				)
				(justify left)
			)
		)
		(property "Value" ""
			(at 0 0 180)
			(layer "F.Fab")
			(effects
				(font
					(size 1.27 1.27)
				)
			)
		)
		(duplicate_pad_numbers_are_jumpers no)
		(fp_line
			(start 1.249934 3.860038)
			(end 1.249934 0.6477)
			(stroke
				(width 0.1524)
				(type default)
			)
			(layer "F.SilkS")
		)
		(fp_line
			(start 1.249934 -0.6477)
			(end 1.249934 -3.860038)
			(stroke
				(width 0.1524)
				(type default)
			)
			(layer "F.SilkS")
		)
		(fp_line
			(start 1.249934 -3.860038)
			(end -1.249934 -3.860038)
			(stroke
				(width 0.1524)
				(type default)
			)
			(layer "F.SilkS")
		)
		(fp_line
			(start -1.249934 3.860038)
			(end 1.249934 3.860038)
			(stroke
				(width 0.1524)
				(type default)
			)
			(layer "F.SilkS")
		)
		(fp_line
			(start -1.249934 3.1877)
			(end -1.249934 3.860038)
			(stroke
				(width 0.1524)
				(type default)
			)
			(layer "F.SilkS")
		)
		(fp_line
			(start -1.249934 -1.8923)
			(end -1.249934 1.8923)
			(stroke
				(width 0.1524)
				(type default)
			)
			(layer "F.SilkS")
		)
		(fp_line
			(start -1.249934 -3.860038)
			(end -1.249934 -3.1877)
			(stroke
				(width 0.1524)
				(type default)
			)
			(layer "F.SilkS")
		)
		(fp_poly
			(pts
				(xy -3.7084 -3.9116) (xy -2.6924 -3.4036) (xy -3.7084 -2.8956)
			)
			(stroke
				(width 0)
				(type default)
			)
			(fill yes)
			(layer "F.SilkS")
		)
		(fp_line
			(start 1.249934 3.860038)
			(end 1.249934 -3.860038)
			(stroke
				(width 0.1)
				(type default)
			)
			(layer "F.Fab")
		)
		(fp_line
			(start 1.249934 -3.860038)
			(end -1.249934 -3.860038)
			(stroke
				(width 0.1)
				(type default)
			)
			(layer "F.Fab")
		)
		(fp_line
			(start -1.249934 3.860038)
			(end 1.249934 3.860038)
			(stroke
				(width 0.1)
				(type default)
			)
			(layer "F.Fab")
		)
		(fp_line
			(start -1.249934 -3.860038)
			(end -1.249934 3.860038)
			(stroke
				(width 0.1)
				(type default)
			)
			(layer "F.Fab")
		)
		(fp_poly
			(pts
				(xy -4.2164 -3.048) (xy -3.2004 -2.54) (xy -4.2164 -2.032)
			)
			(stroke
				(width 0)
				(type default)
			)
			(fill yes)
			(layer "F.Fab")
		)
		(pad "1" smd rect
			(at -1.374902 -2.54 90)
			(size 1.016 2.7686)
			(layers "F.Cu" "F.Mask" "F.Paste")
			(net "PU_J1_P1")
		)
		(pad "2" smd rect
			(at 1.374902 0 90)
			(size 1.016 2.7686)
			(layers "F.Cu" "F.Mask" "F.Paste")
			(net "FLASH_LATCH_Q_N_R2")
		)
		(pad "3" smd rect
			(at -1.374902 2.54 90)
			(size 1.016 2.7686)
			(layers "F.Cu" "F.Mask" "F.Paste")
			(net "NC_J1_P3")
		)
	)
	(footprint ""
		(layer "F.Cu")
		(at 54.473856 -30.867604 90)
		(property "Reference" "R521"
			(at 0 0 90)
			(layer "F.SilkS")
			(hide yes)
			(effects
				(font
					(size 1.27 1.27)
				)
			)
		)
		(property "Value" ""
			(at 0 0 90)
			(layer "F.Fab")
			(effects
				(font
					(size 1.27 1.27)
				)
			)
		)
		(duplicate_pad_numbers_are_jumpers no)
		(fp_line
			(start 0.7874 -0.4064)
			(end 0.7874 0.4064)
			(stroke
				(width 0.1524)
				(type default)
			)
			(layer "F.SilkS")
		)
		(fp_line
			(start -0.7874 -0.4064)
			(end 0.7874 -0.4064)
			(stroke
				(width 0.1524)
				(type default)
			)
			(layer "F.SilkS")
		)
		(fp_line
			(start 0.7874 0.4064)
			(end -0.7874 0.4064)
			(stroke
				(width 0.1524)
				(type default)
			)
			(layer "F.SilkS")
		)
		(fp_line
			(start -0.7874 0.4064)
			(end -0.7874 -0.4064)
			(stroke
				(width 0.1524)
				(type default)
			)
			(layer "F.SilkS")
		)
		(fp_line
			(start -0.12065 -0.305054)
			(end -0.12065 -0.2794)
			(stroke
				(width 0.1)
				(type default)
			)
			(layer "F.Fab")
		)
		(fp_line
			(start -0.67945 -0.305054)
			(end -0.12065 -0.305054)
			(stroke
				(width 0.1)
				(type default)
			)
			(layer "F.Fab")
		)
		(fp_line
			(start 0.67945 -0.3048)
			(end 0.67945 0.3048)
			(stroke
				(width 0.1)
				(type default)
			)
			(layer "F.Fab")
		)
		(fp_line
			(start 0.12065 -0.3048)
			(end 0.67945 -0.3048)
			(stroke
				(width 0.1)
				(type default)
			)
			(layer "F.Fab")
		)
		(fp_line
			(start 0.12065 -0.2794)
			(end 0.12065 -0.3048)
			(stroke
				(width 0.1)
				(type default)
			)
			(layer "F.Fab")
		)
		(fp_line
			(start -0.12065 -0.2794)
			(end 0.12065 -0.2794)
			(stroke
				(width 0.1)
				(type default)
			)
			(layer "F.Fab")
		)
		(fp_line
			(start 0.120396 0.2794)
			(end -0.12065 0.2794)
			(stroke
				(width 0.1)
				(type default)
			)
			(layer "F.Fab")
		)
		(fp_line
			(start -0.12065 0.2794)
			(end -0.12065 0.3048)
			(stroke
				(width 0.1)
				(type default)
			)
			(layer "F.Fab")
		)
		(fp_line
			(start 0.67945 0.3048)
			(end 0.120396 0.3048)
			(stroke
				(width 0.1)
				(type default)
			)
			(layer "F.Fab")
		)
		(fp_line
			(start 0.120396 0.3048)
			(end 0.120396 0.2794)
			(stroke
				(width 0.1)
				(type default)
			)
			(layer "F.Fab")
		)
		(fp_line
			(start -0.12065 0.3048)
			(end -0.67945 0.3048)
			(stroke
				(width 0.1)
				(type default)
			)
			(layer "F.Fab")
		)
		(fp_line
			(start -0.67945 0.3048)
			(end -0.67945 -0.305054)
			(stroke
				(width 0.1)
				(type default)
			)
			(layer "F.Fab")
		)
		(pad "1" smd circle
			(at -0.40005 0 90)
			(size 0 0)
			(layers "F.Cu" "F.Mask" "F.Paste")
			(net "P3V3_AUX")
		)
		(pad "2" smd circle
			(at 0.40005 0 90)
			(size 0 0)
			(layers "F.Cu" "F.Mask" "F.Paste")
			(net "SMB_BMC_MM10_SDA")
		)
	)
	(footprint ""
		(layer "F.Cu")
		(at 39.905686 -46.391576 180)
		(property "Reference" "R817"
			(at 0 0 180)
			(layer "F.SilkS")
			(hide yes)
			(effects
				(font
					(size 1.27 1.27)
				)
			)
		)
		(property "Value" ""
			(at 0 0 180)
			(layer "F.Fab")
			(effects
				(font
					(size 1.27 1.27)
				)
			)
		)
		(duplicate_pad_numbers_are_jumpers no)
		(fp_line
			(start 0.7874 0.4064)
			(end -0.7874 0.4064)
			(stroke
				(width 0.1524)
				(type default)
			)
			(layer "F.SilkS")
		)
		(fp_line
			(start 0.7874 -0.4064)
			(end 0.7874 0.4064)
			(stroke
				(width 0.1524)
				(type default)
			)
			(layer "F.SilkS")
		)
		(fp_line
			(start -0.7874 0.4064)
			(end -0.7874 -0.4064)
			(stroke
				(width 0.1524)
				(type default)
			)
			(layer "F.SilkS")
		)
		(fp_line
			(start -0.7874 -0.4064)
			(end 0.7874 -0.4064)
			(stroke
				(width 0.1524)
				(type default)
			)
			(layer "F.SilkS")
		)
		(fp_line
			(start 0.67945 0.3048)
			(end 0.120396 0.3048)
			(stroke
				(width 0.1)
				(type default)
			)
			(layer "F.Fab")
		)
		(fp_line
			(start 0.67945 -0.3048)
			(end 0.67945 0.3048)
			(stroke
				(width 0.1)
				(type default)
			)
			(layer "F.Fab")
		)
		(fp_line
			(start 0.12065 -0.2794)
			(end 0.12065 -0.3048)
			(stroke
				(width 0.1)
				(type default)
			)
			(layer "F.Fab")
		)
		(fp_line
			(start 0.12065 -0.3048)
			(end 0.67945 -0.3048)
			(stroke
				(width 0.1)
				(type default)
			)
			(layer "F.Fab")
		)
		(fp_line
			(start 0.120396 0.3048)
			(end 0.120396 0.2794)
			(stroke
				(width 0.1)
				(type default)
			)
			(layer "F.Fab")
		)
		(fp_line
			(start 0.120396 0.2794)
			(end -0.12065 0.2794)
			(stroke
				(width 0.1)
				(type default)
			)
			(layer "F.Fab")
		)
		(fp_line
			(start -0.12065 0.3048)
			(end -0.67945 0.3048)
			(stroke
				(width 0.1)
				(type default)
			)
			(layer "F.Fab")
		)
		(fp_line
			(start -0.12065 0.2794)
			(end -0.12065 0.3048)
			(stroke
				(width 0.1)
				(type default)
			)
			(layer "F.Fab")
		)
		(fp_line
			(start -0.12065 -0.2794)
			(end 0.12065 -0.2794)
			(stroke
				(width 0.1)
				(type default)
			)
			(layer "F.Fab")
		)
		(fp_line
			(start -0.12065 -0.305054)
			(end -0.12065 -0.2794)
			(stroke
				(width 0.1)
				(type default)
			)
			(layer "F.Fab")
		)
		(fp_line
			(start -0.67945 0.3048)
			(end -0.67945 -0.305054)
			(stroke
				(width 0.1)
				(type default)
			)
			(layer "F.Fab")
		)
		(fp_line
			(start -0.67945 -0.305054)
			(end -0.12065 -0.305054)
			(stroke
				(width 0.1)
				(type default)
			)
			(layer "F.Fab")
		)
		(pad "1" smd circle
			(at -0.40005 0 180)
			(size 0 0)
			(layers "F.Cu" "F.Mask" "F.Paste")
			(net "SMB_BMC_MM13_R_SCL")
		)
		(pad "2" smd circle
			(at 0.40005 0 180)
			(size 0 0)
			(layers "F.Cu" "F.Mask" "F.Paste")
			(net "GND")
		)
	)
	(footprint ""
		(layer "F.Cu")
		(at 64.4144 -28.0162 180)
		(property "Reference" "R440"
			(at 0 0 180)
			(layer "F.SilkS")
			(hide yes)
			(effects
				(font
					(size 1.27 1.27)
				)
			)
		)
		(property "Value" ""
			(at 0 0 180)
			(layer "F.Fab")
			(effects
				(font
					(size 1.27 1.27)
				)
			)
		)
		(duplicate_pad_numbers_are_jumpers no)
		(fp_line
			(start 0.7874 0.4064)
			(end -0.3048 0.4064)
			(stroke
				(width 0.1524)
				(type default)
			)
			(layer "F.SilkS")
		)
		(fp_line
			(start 0.7874 -0.4064)
			(end 0.7874 0.4064)
			(stroke
				(width 0.1524)
				(type default)
			)
			(layer "F.SilkS")
		)
		(fp_line
			(start -0.381 -0.4064)
			(end 0.7874 -0.4064)
			(stroke
				(width 0.1524)
				(type default)
			)
			(layer "F.SilkS")
		)
		(fp_line
			(start 0.67945 0.3048)
			(end 0.120396 0.3048)
			(stroke
				(width 0.1)
				(type default)
			)
			(layer "F.Fab")
		)
		(fp_line
			(start 0.67945 -0.3048)
			(end 0.67945 0.3048)
			(stroke
				(width 0.1)
				(type default)
			)
			(layer "F.Fab")
		)
		(fp_line
			(start 0.12065 -0.2794)
			(end 0.12065 -0.3048)
			(stroke
				(width 0.1)
				(type default)
			)
			(layer "F.Fab")
		)
		(fp_line
			(start 0.12065 -0.3048)
			(end 0.67945 -0.3048)
			(stroke
				(width 0.1)
				(type default)
			)
			(layer "F.Fab")
		)
		(fp_line
			(start 0.120396 0.3048)
			(end 0.120396 0.2794)
			(stroke
				(width 0.1)
				(type default)
			)
			(layer "F.Fab")
		)
		(fp_line
			(start 0.120396 0.2794)
			(end -0.12065 0.2794)
			(stroke
				(width 0.1)
				(type default)
			)
			(layer "F.Fab")
		)
		(fp_line
			(start -0.12065 0.3048)
			(end -0.67945 0.3048)
			(stroke
				(width 0.1)
				(type default)
			)
			(layer "F.Fab")
		)
		(fp_line
			(start -0.12065 0.2794)
			(end -0.12065 0.3048)
			(stroke
				(width 0.1)
				(type default)
			)
			(layer "F.Fab")
		)
		(fp_line
			(start -0.12065 -0.2794)
			(end 0.12065 -0.2794)
			(stroke
				(width 0.1)
				(type default)
			)
			(layer "F.Fab")
		)
		(fp_line
			(start -0.12065 -0.305054)
			(end -0.12065 -0.2794)
			(stroke
				(width 0.1)
				(type default)
			)
			(layer "F.Fab")
		)
		(fp_line
			(start -0.67945 0.3048)
			(end -0.67945 -0.305054)
			(stroke
				(width 0.1)
				(type default)
			)
			(layer "F.Fab")
		)
		(fp_line
			(start -0.67945 -0.305054)
			(end -0.12065 -0.305054)
			(stroke
				(width 0.1)
				(type default)
			)
			(layer "F.Fab")
		)
		(pad "1" smd circle
			(at -0.40005 0 180)
			(size 0 0)
			(layers "F.Cu" "F.Mask" "F.Paste")
			(net "USB_HOST_BMC_A_DP")
		)
		(pad "2" smd circle
			(at 0.40005 0 180)
			(size 0 0)
			(layers "F.Cu" "F.Mask" "F.Paste")
			(net "GND")
		)
	)
)
